#ISCELL
  mstr_misc dns *
  *
#ISCELL
  mstr_symbols cad_note *
  *
#ISCELL
  mstr_symbols design_note *
  *
#ISCELL
  mstr_symbols intel_corp_bpage *
  *
#CELL
  mstr_ttl ttl08 *
  page170_i10
#CELL
  mstr_ttl ttl08 *
  page170_i11
#CELL
  mstr_ttl ttl08 *
  page170_i12
#ISCELL
  mstr_standard offpage *
  page170_i15
#ISCELL
  mstr_standard offpage *
  page170_i16
#ISCELL
  mstr_standard offpage *
  page170_i17
#ISCELL
  mstr_standard offpage *
  page170_i18
#ISCELL
  mstr_standard offpage *
  page170_i19
#CELL
  mstr_discrete res *
  page170_i2
#CELL
  mstr_ttl ttl1g126_a *
  page170_i20
#ISCELL
  mstr_symbols p3v3_stby *
  page170_i3
#CELL
  dev_discrete cap_a *
  page170_i30
#ISCELL
  mstr_symbols gnd *
  page170_i31
#ISCELL
  mstr_symbols p3v3_stby *
  page170_i32
#CELL
  dev_discrete cap_a *
  page170_i33
#ISCELL
  mstr_symbols gnd *
  page170_i34
#ISCELL
  mstr_symbols p3v3_stby *
  page170_i35
#CELL
  mstr_ttl ttl1g126_a *
  page170_i38
#ISCELL
  mstr_symbols p3v3_stby *
  page170_i39
#CELL
  mstr_ttl ttl1g07_a *
  page170_i4
#CELL
  dev_discrete cap_a *
  page170_i40
#ISCELL
  mstr_symbols gnd *
  page170_i41
#CELL
  mstr_discrete cap *
  page170_i42
#ISCELL
  mstr_symbols gnd *
  page170_i43
#ISCELL
  mstr_standard offpage *
  page170_i44
#CELL
  mstr_ttl ttl1g07_a *
  page170_i46
#ISCELL
  mstr_standard offpage *
  page170_i47
#ISCELL
  mstr_symbols p3v3_stby *
  page170_i48
#CELL
  dev_discrete cap_a *
  page170_i49
#ISCELL
  mstr_standard offpage *
  page170_i5
#ISCELL
  mstr_symbols gnd *
  page170_i50
#CELL
  mstr_discrete res *
  page170_i51
#CELL
  mstr_discrete res *
  page170_i52
#ISCELL
  mstr_symbols p3v3_stby *
  page170_i53
#CELL
  mstr_discrete res *
  page170_i54
#ISCELL
  mstr_symbols p3v3_stby *
  page170_i55
#CELL
  mstr_discrete res *
  page170_i56
#CELL
  mstr_discrete fet_n *
  page170_i58
#ISCELL
  mstr_standard offpage *
  page170_i59
#ISCELL
  mstr_symbols p3v3_stby *
  page170_i6
#ISCELL
  mstr_symbols gnd *
  page170_i60
#CELL
  mstr_discrete res *
  page170_i61
#ISCELL
  mstr_symbols p3v3_stby *
  page170_i62
#CELL
  mstr_discrete res *
  page170_i63
#ISCELL
  mstr_symbols gnd *
  page170_i64
#CELL
  mstr_discrete res *
  page170_i65
#ISCELL
  mstr_symbols p3v3_stby *
  page170_i66
#CELL
  mstr_discrete fet_n *
  page170_i67
#ISCELL
  mstr_symbols gnd *
  page170_i68
#ISCELL
  mstr_standard offpage *
  page170_i69
#ISCELL
  mstr_symbols gnd *
  page170_i7
#ISCELL
  mstr_symbols p3v3_stby *
  page170_i70
#CELL
  mstr_discrete res *
  page170_i71
#ISCELL
  mstr_symbols p3v3_stby *
  page170_i72
#CELL
  mstr_discrete res *
  page170_i73
#CELL
  mstr_discrete res *
  page170_i74
#CELL
  dev_discrete cap_a *
  page170_i8
